# T6G (Grand Teton) — schematic netlist excerpt (pin names and nets, part order shuffled) for the footprints in the layout excerpt that follows; sources: Cadence DE-HDL packaged netlist, KiCad conversion of 04192023_DAF0TMB3IC0_F0TG_MB_C_brd_V02_OCP.brd

PC6634_2  Q_CAP  3300PF 50V 10% X7R  pkg 0402  page 365 : A = SW_P12V_AUX_P0V9_RETIMER_CPU1_FLT ; B = GND
R611  Q_RES  0 5% CHIP  pkg 0201LF  page 287 : A = CLK_100M_RETIMER_CPU0_P1_R_DP ; B = CLK_100M_RETIMER_CPU0_P1_DP
R3028  Q_RES  100K 1% EMPTY  pkg 0402LF  page 127 : A = FM_SMB_1_ALERT_GPU_N ; B = GND

(kicad_pcb
	(version 20260206)
	(generator "pcbnew")
	(generator_version "10.0")
	(general
		(thickness 1.6)
		(legacy_teardrops no)
	)
	(paper "A4")
	(title_block
		(title "04192023_DAF0TMB3IC0_F0TG_MB_C_brd_V02_OCP.brd")
		(comment 1 "Grand Teton / footprints 3349-3351 of 8354")
	)
	(layers
		(0 "F.Cu" signal "TOP")
		(4 "In1.Cu" signal "GND")
		(6 "In2.Cu" signal "IN1")
		(8 "In3.Cu" signal "GND1")
		(10 "In4.Cu" signal "IN2")
		(12 "In5.Cu" signal "GND2")
		(14 "In6.Cu" signal "IN3")
		(16 "In7.Cu" signal "GND3")
		(18 "In8.Cu" signal "VCC")
		(20 "In9.Cu" signal "VCC1")
		(22 "In10.Cu" signal "GND4")
		(24 "In11.Cu" signal "IN4")
		(26 "In12.Cu" signal "GND5")
		(28 "In13.Cu" signal "IN5")
		(30 "In14.Cu" signal "GND6")
		(32 "In15.Cu" signal "IN6")
		(34 "In16.Cu" signal "GND7")
		(2 "B.Cu" signal "BOTTOM")
		(9 "F.Adhes" user "F.Adhesive")
		(11 "B.Adhes" user "B.Adhesive")
		(13 "F.Paste" user "Package Geometry/Pastemask Top")
		(15 "B.Paste" user "Package Geometry/Pastemask Bottom")
		(5 "F.SilkS" user "Ref Des/Silkscreen Top")
		(7 "B.SilkS" user "Ref Des/Silkscreen Bottom")
		(1 "F.Mask" user "Board Geometry/Soldermask Top")
		(3 "B.Mask" user "Board Geometry/Soldermask Bottom")
		(17 "Dwgs.User" user "User.Drawings")
		(19 "Cmts.User" user "User.Comments")
		(21 "Eco1.User" user "User.Eco1")
		(23 "Eco2.User" user "User.Eco2")
		(25 "Edge.Cuts" user "Board Geometry/Outline")
		(27 "Margin" user)
		(31 "F.CrtYd" user "Package Geometry/Place Bound Top")
		(29 "B.CrtYd" user "Package Geometry/Place Bound Bottom")
		(35 "F.Fab" user "Ref Des/Assembly Top")
		(33 "B.Fab" user "Ref Des/Assembly Bottom")
	)
	(footprint ""
		(layer "F.Cu")
		(at 115.08359 -417.939982 90)
		(property "Reference" "R3028"
			(at 0 0 90)
			(layer "F.SilkS")
			(hide yes)
			(effects
				(font
					(size 1.27 1.27)
				)
			)
		)
		(property "Value" ""
			(at 0 0 90)
			(layer "F.Fab")
			(effects
				(font
					(size 1.27 1.27)
				)
			)
		)
		(duplicate_pad_numbers_are_jumpers no)
		(fp_line
			(start 0.7874 -0.4064)
			(end 0.7874 0.4064)
			(stroke
				(width 0.1524)
				(type default)
			)
			(layer "F.SilkS")
		)
		(fp_line
			(start -0.7874 -0.4064)
			(end 0.7874 -0.4064)
			(stroke
				(width 0.1524)
				(type default)
			)
			(layer "F.SilkS")
		)
		(fp_line
			(start 0.7874 0.4064)
			(end -0.7874 0.4064)
			(stroke
				(width 0.1524)
				(type default)
			)
			(layer "F.SilkS")
		)
		(fp_line
			(start -0.7874 0.4064)
			(end -0.7874 -0.4064)
			(stroke
				(width 0.1524)
				(type default)
			)
			(layer "F.SilkS")
		)
		(fp_line
			(start -0.12065 -0.305054)
			(end -0.12065 -0.2794)
			(stroke
				(width 0.1)
				(type default)
			)
			(layer "F.Fab")
		)
		(fp_line
			(start -0.67945 -0.305054)
			(end -0.12065 -0.305054)
			(stroke
				(width 0.1)
				(type default)
			)
			(layer "F.Fab")
		)
		(fp_line
			(start 0.67945 -0.3048)
			(end 0.67945 0.3048)
			(stroke
				(width 0.1)
				(type default)
			)
			(layer "F.Fab")
		)
		(fp_line
			(start 0.12065 -0.3048)
			(end 0.67945 -0.3048)
			(stroke
				(width 0.1)
				(type default)
			)
			(layer "F.Fab")
		)
		(fp_line
			(start 0.12065 -0.2794)
			(end 0.12065 -0.3048)
			(stroke
				(width 0.1)
				(type default)
			)
			(layer "F.Fab")
		)
		(fp_line
			(start -0.12065 -0.2794)
			(end 0.12065 -0.2794)
			(stroke
				(width 0.1)
				(type default)
			)
			(layer "F.Fab")
		)
		(fp_line
			(start 0.120396 0.2794)
			(end -0.12065 0.2794)
			(stroke
				(width 0.1)
				(type default)
			)
			(layer "F.Fab")
		)
		(fp_line
			(start -0.12065 0.2794)
			(end -0.12065 0.3048)
			(stroke
				(width 0.1)
				(type default)
			)
			(layer "F.Fab")
		)
		(fp_line
			(start 0.67945 0.3048)
			(end 0.120396 0.3048)
			(stroke
				(width 0.1)
				(type default)
			)
			(layer "F.Fab")
		)
		(fp_line
			(start 0.120396 0.3048)
			(end 0.120396 0.2794)
			(stroke
				(width 0.1)
				(type default)
			)
			(layer "F.Fab")
		)
		(fp_line
			(start -0.12065 0.3048)
			(end -0.67945 0.3048)
			(stroke
				(width 0.1)
				(type default)
			)
			(layer "F.Fab")
		)
		(fp_line
			(start -0.67945 0.3048)
			(end -0.67945 -0.305054)
			(stroke
				(width 0.1)
				(type default)
			)
			(layer "F.Fab")
		)
		(pad "1" smd circle
			(at -0.40005 0 90)
			(size 0 0)
			(layers "F.Cu" "F.Mask" "F.Paste")
			(net "FM_SMB_1_ALERT_GPU_N")
		)
		(pad "2" smd circle
			(at 0.40005 0 90)
			(size 0 0)
			(layers "F.Cu" "F.Mask" "F.Paste")
			(net "GND")
		)
	)
	(footprint ""
		(layer "F.Cu")
		(at 331.055472 -396.146274)
		(property "Reference" "R611"
			(at 0 0 0)
			(layer "F.SilkS")
			(hide yes)
			(effects
				(font
					(size 1.27 1.27)
				)
			)
		)
		(property "Value" ""
			(at 0 0 0)
			(layer "F.Fab")
			(effects
				(font
					(size 1.27 1.27)
				)
			)
		)
		(duplicate_pad_numbers_are_jumpers no)
		(fp_line
			(start -0.32512 -0.175006)
			(end 0.32512 -0.175006)
			(stroke
				(width 0.1)
				(type default)
			)
			(layer "F.Fab")
		)
		(fp_line
			(start -0.32512 0.175006)
			(end -0.32512 -0.175006)
			(stroke
				(width 0.1)
				(type default)
			)
			(layer "F.Fab")
		)
		(fp_line
			(start 0.32512 -0.175006)
			(end 0.32512 0.175006)
			(stroke
				(width 0.1)
				(type default)
			)
			(layer "F.Fab")
		)
		(fp_line
			(start 0.32512 0.175006)
			(end -0.32512 0.175006)
			(stroke
				(width 0.1)
				(type default)
			)
			(layer "F.Fab")
		)
		(pad "1" smd rect
			(at -0.2667 0)
			(size 0.3048 0.381)
			(layers "F.Cu" "F.Mask" "F.Paste")
			(net "CLK_100M_RETIMER_CPU0_P1_R_DP")
		)
		(pad "2" smd rect
			(at 0.2667 0 180)
			(size 0.3048 0.381)
			(layers "F.Cu" "F.Mask" "F.Paste")
			(net "CLK_100M_RETIMER_CPU0_P1_DP")
		)
	)
	(footprint ""
		(layer "F.Cu")
		(at 29.226764 -388.931658 -90)
		(property "Reference" "PC6634_2"
			(at 0 0 270)
			(layer "F.SilkS")
			(hide yes)
			(effects
				(font
					(size 1.27 1.27)
				)
			)
		)
		(property "Value" ""
			(at 0 0 270)
			(layer "F.Fab")
			(effects
				(font
					(size 1.27 1.27)
				)
			)
		)
		(duplicate_pad_numbers_are_jumpers no)
		(fp_line
			(start -0.7874 0.4064)
			(end -0.7874 -0.4064)
			(stroke
				(width 0.1524)
				(type default)
			)
			(layer "F.SilkS")
		)
		(fp_line
			(start 0.7874 0.4064)
			(end -0.7874 0.4064)
			(stroke
				(width 0.1524)
				(type default)
			)
			(layer "F.SilkS")
		)
		(fp_line
			(start -0.7874 -0.4064)
			(end 0.7874 -0.4064)
			(stroke
				(width 0.1524)
				(type default)
			)
			(layer "F.SilkS")
		)
		(fp_line
			(start 0.7874 -0.4064)
			(end 0.7874 0.4064)
			(stroke
				(width 0.1524)
				(type default)
			)
			(layer "F.SilkS")
		)
		(fp_line
			(start -0.67945 0.3048)
			(end -0.67945 -0.305054)
			(stroke
				(width 0.1)
				(type default)
			)
			(layer "F.Fab")
		)
		(fp_line
			(start -0.12065 0.3048)
			(end -0.67945 0.3048)
			(stroke
				(width 0.1)
				(type default)
			)
			(layer "F.Fab")
		)
		(fp_line
			(start 0.120396 0.3048)
			(end 0.120396 0.2794)
			(stroke
				(width 0.1)
				(type default)
			)
			(layer "F.Fab")
		)
		(fp_line
			(start 0.67945 0.3048)
			(end 0.120396 0.3048)
			(stroke
				(width 0.1)
				(type default)
			)
			(layer "F.Fab")
		)
		(fp_line
			(start -0.12065 0.2794)
			(end -0.12065 0.3048)
			(stroke
				(width 0.1)
				(type default)
			)
			(layer "F.Fab")
		)
		(fp_line
			(start 0.120396 0.2794)
			(end -0.12065 0.2794)
			(stroke
				(width 0.1)
				(type default)
			)
			(layer "F.Fab")
		)
		(fp_line
			(start -0.12065 -0.2794)
			(end 0.12065 -0.2794)
			(stroke
				(width 0.1)
				(type default)
			)
			(layer "F.Fab")
		)
		(fp_line
			(start 0.12065 -0.2794)
			(end 0.12065 -0.3048)
			(stroke
				(width 0.1)
				(type default)
			)
			(layer "F.Fab")
		)
		(fp_line
			(start 0.12065 -0.3048)
			(end 0.67945 -0.3048)
			(stroke
				(width 0.1)
				(type default)
			)
			(layer "F.Fab")
		)
		(fp_line
			(start 0.67945 -0.3048)
			(end 0.67945 0.3048)
			(stroke
				(width 0.1)
				(type default)
			)
			(layer "F.Fab")
		)
		(fp_line
			(start -0.67945 -0.305054)
			(end -0.12065 -0.305054)
			(stroke
				(width 0.1)
				(type default)
			)
			(layer "F.Fab")
		)
		(fp_line
			(start -0.12065 -0.305054)
			(end -0.12065 -0.2794)
			(stroke
				(width 0.1)
				(type default)
			)
			(layer "F.Fab")
		)
		(pad "1" smd circle
			(at -0.40005 0 270)
			(size 0 0)
			(layers "F.Cu" "F.Mask" "F.Paste")
			(net "SW_P12V_AUX_P0V9_RETIMER_CPU1_FLT")
		)
		(pad "2" smd circle
			(at 0.40005 0 270)
			(size 0 0)
			(layers "F.Cu" "F.Mask" "F.Paste")
			(net "GND")
		)
	)
)
